#ISCELL
  pure_quanta quanta_title_block_c *
  *
#ISCELL
  pure_quanta_power cad_note *
  *
#CELL
  pure_quanta q_res *
  page112_i1
#ISCELL
  standard offpage *
  page112_i10
#CELL
  pure_quanta q_cap *
  page112_i11
#CELL
  pure_quanta q_cap *
  page112_i12
#CELL
  pure_quanta q_cap *
  page112_i13
#CELL
  pure_quanta q_cap *
  page112_i14
#ISCELL
  standard offpage *
  page112_i15
#ISCELL
  standard offpage *
  page112_i16
#ISCELL
  standard offpage *
  page112_i17
#ISCELL
  standard offpage *
  page112_i18
#ISCELL
  standard offpage *
  page112_i19
#CELL
  pure_quanta q_res *
  page112_i2
#ISCELL
  standard offpage *
  page112_i20
#CELL
  pure_quanta q_res *
  page112_i21
#CELL
  pure_quanta q_res *
  page112_i22
#CELL
  pure_quanta q_res *
  page112_i23
#CELL
  pure_quanta q_res *
  page112_i24
#ISCELL
  standard offpage *
  page112_i25
#ISCELL
  standard offpage *
  page112_i26
#CELL
  pure_quanta q_res *
  page112_i3
#ISCELL
  standard offpage *
  page112_i33
#ISCELL
  standard offpage *
  page112_i34
#CELL
  pure_quanta q_cap *
  page112_i35
#CELL
  pure_quanta q_cap *
  page112_i36
#ISCELL
  standard offpage *
  page112_i37
#ISCELL
  standard offpage *
  page112_i38
#ISCELL
  standard offpage *
  page112_i39
#ISCELL
  standard offpage *
  page112_i4
#ISCELL
  standard offpage *
  page112_i40
#CELL
  pure_quanta q_cap *
  page112_i43
#CELL
  pure_quanta q_cap *
  page112_i44
#ISCELL
  standard offpage *
  page112_i45
#ISCELL
  standard offpage *
  page112_i46
#ISCELL
  standard offpage *
  page112_i47
#ISCELL
  standard offpage *
  page112_i48
#ISCELL
  standard offpage *
  page112_i5
#ISCELL
  standard offpage *
  page112_i6
#ISCELL
  standard offpage *
  page112_i7
#CELL
  pure_quanta q_res *
  page112_i8
#ISCELL
  standard offpage *
  page112_i9
